(kicad_pcb
	(version 20241229)
	(generator "pcbnew")
	(generator_version "9.0")
	(general
		(thickness 1.6296)
		(legacy_teardrops no)
	)
	(paper "A3")
	(title_block
		(title "Thunderbolt to 10GbE adapter")
		(date "2026-04-21")
		(rev "1.1.0")
		(company "Antmicro Ltd")
		(comment 1 "www.antmicro.com")
		(comment 9 "footprints 128-132 of 703")
	)
	(layers
		(0 "F.Cu" signal)
		(4 "In1.Cu" signal)
		(6 "In2.Cu" signal)
		(8 "In3.Cu" signal)
		(10 "In4.Cu" signal)
		(12 "In5.Cu" signal)
		(14 "In6.Cu" signal)
		(2 "B.Cu" signal)
		(9 "F.Adhes" user "F.Adhesive")
		(11 "B.Adhes" user "B.Adhesive")
		(13 "F.Paste" user)
		(15 "B.Paste" user)
		(5 "F.SilkS" user "F.Silkscreen")
		(7 "B.SilkS" user "B.Silkscreen")
		(1 "F.Mask" user)
		(3 "B.Mask" user)
		(17 "Dwgs.User" user "User.Drawings")
		(19 "Cmts.User" user "User.Comments")
		(21 "Eco1.User" user "User.Eco1")
		(23 "Eco2.User" user "User.Eco2")
		(25 "Edge.Cuts" user)
		(27 "Margin" user)
		(31 "F.CrtYd" user "F.Courtyard")
		(29 "B.CrtYd" user "B.Courtyard")
		(35 "F.Fab" user)
		(33 "B.Fab" user)
	)
	(footprint "antmicro-footprints:R_0603_1608Metric"
		(layer "F.Cu")
		(at 145.35 57.3 90)
		(descr "Resistor SMD 0603")
		(tags "resistor SMD 0603")
		(property "Reference" "R234"
			(at -4 0.65 90)
			(layer "F.SilkS")
			(effects
				(font
					(size 0.7 0.7)
					(thickness 0.15)
				)
				(justify left bottom)
			)
		)
		(property "Value" "R_0R_22.4A_0603"
			(at 0 1.6 90)
			(layer "F.Fab")
			(effects
				(font
					(size 0.7 0.7)
					(thickness 0.15)
				)
				(justify left bottom)
			)
		)
		(property "Datasheet" "https://fscdn.rohm.com/en/products/databook/datasheet/passive/resistor/chip_resistor/pmr-jpw-e.pdf"
			(at 0 0 90)
			(layer "F.Fab")
			(hide yes)
			(effects
				(font
					(size 1.27 1.27)
					(thickness 0.15)
				)
			)
		)
		(property "Description" "SMD Chip Resistor"
			(at 0 0 90)
			(layer "F.Fab")
			(hide yes)
			(effects
				(font
					(size 1.27 1.27)
					(thickness 0.15)
				)
			)
		)
		(property "MPN" "PMR03EZPJ000"
			(at 0 0 90)
			(unlocked yes)
			(layer "F.Fab")
			(hide yes)
			(effects
				(font
					(size 1 1)
					(thickness 0.15)
				)
			)
		)
		(property "Manufacturer" "ROHM Semiconductor"
			(at 0 0 90)
			(unlocked yes)
			(layer "F.Fab")
			(hide yes)
			(effects
				(font
					(size 1 1)
					(thickness 0.15)
				)
			)
		)
		(property "Val" "0R"
			(at 0 0 90)
			(unlocked yes)
			(layer "F.Fab")
			(hide yes)
			(effects
				(font
					(size 1 1)
					(thickness 0.15)
				)
			)
		)
		(property "Max. Curr." "22.4A"
			(at 0 0 90)
			(unlocked yes)
			(layer "F.Fab")
			(hide yes)
			(effects
				(font
					(size 1 1)
					(thickness 0.15)
				)
			)
		)
		(property "Author" "Antmicro"
			(at 0 0 90)
			(unlocked yes)
			(layer "F.Fab")
			(hide yes)
			(effects
				(font
					(size 1 1)
					(thickness 0.15)
				)
			)
		)
		(property "License" "Apache-2.0"
			(at 0 0 90)
			(unlocked yes)
			(layer "F.Fab")
			(hide yes)
			(effects
				(font
					(size 1 1)
					(thickness 0.15)
				)
			)
		)
		(property "Tolerance" "template_tolerance"
			(at 0 0 90)
			(unlocked yes)
			(layer "F.Fab")
			(hide yes)
			(effects
				(font
					(size 1 1)
					(thickness 0.15)
				)
			)
		)
		(sheetname "/Power input/")
		(sheetfile "power_input.kicad_sch")
		(attr smd)
		(fp_line
			(start -0.15 -0.4)
			(end 0.15 -0.4)
			(stroke
				(width 0.15)
				(type solid)
			)
			(layer "F.SilkS")
		)
		(fp_line
			(start -0.15 0.4)
			(end 0.15 0.4)
			(stroke
				(width 0.15)
				(type solid)
			)
			(layer "F.SilkS")
		)
		(fp_rect
			(start -1.25 -0.65)
			(end 1.25 0.65)
			(stroke
				(width 0.05)
				(type solid)
			)
			(fill no)
			(layer "F.CrtYd")
		)
		(fp_rect
			(start -0.8 -0.4)
			(end 0.8 0.4)
			(stroke
				(width 0.15)
				(type solid)
			)
			(fill no)
			(layer "F.Fab")
		)
		(fp_text user "${REFERENCE}"
			(at -1.25 3.898 90)
			(layer "F.Fab")
			(effects
				(font
					(size 0.7 0.7)
					(thickness 0.15)
				)
				(justify left bottom)
			)
		)
		(fp_text user "Author: Antmicro"
			(at -1.25 4.9 90)
			(layer "F.Fab")
			(effects
				(font
					(size 0.7 0.7)
					(thickness 0.15)
				)
				(justify left bottom)
			)
		)
		(fp_text user "License: Apache-2.0"
			(at -1.25 5.9 90)
			(layer "F.Fab")
			(effects
				(font
					(size 0.7 0.7)
					(thickness 0.15)
				)
				(justify left bottom)
			)
		)
		(pad "1" smd roundrect
			(at -0.7 0 90)
			(size 0.8 1)
			(layers "F.Cu" "F.Mask" "F.Paste")
			(roundrect_rratio 0.2)
			(net 349 "/Power input/5V_OUT")
			(pintype "passive")
		)
		(pad "2" smd roundrect
			(at 0.7 0 90)
			(size 0.8 1)
			(layers "F.Cu" "F.Mask" "F.Paste")
			(roundrect_rratio 0.2)
			(net 13 "/Power input/5V_JACK")
			(pintype "passive")
		)
	)
	(footprint "antmicro-footprints:R_0402_1005Metric"
		(layer "F.Cu")
		(at 163.6 67.8)
		(descr "Resistor SMD 0402")
		(tags "resistor SMD 0402")
		(property "Reference" "R143"
			(at -1.8 -0.6 0)
			(layer "F.SilkS")
			(effects
				(font
					(size 0.7 0.7)
					(thickness 0.15)
				)
				(justify left bottom)
			)
		)
		(property "Value" "R_2k_0402"
			(at -1.011843 1.772047 0)
			(layer "F.Fab")
			(effects
				(font
					(size 0.7 0.7)
					(thickness 0.15)
				)
				(justify left bottom)
			)
		)
		(property "Datasheet" "https://www.bourns.com/docs/product-datasheets/cr.pdf"
			(at 0 0 0)
			(layer "F.Fab")
			(hide yes)
			(effects
				(font
					(size 1.27 1.27)
					(thickness 0.15)
				)
			)
		)
		(property "Description" "SMD Chip Resistor, 2 kohm, ± 1%, 62.5 mW, 0402 [1005 Metric], Thick Film, General Purpose"
			(at 0 0 0)
			(layer "F.Fab")
			(hide yes)
			(effects
				(font
					(size 1.27 1.27)
					(thickness 0.15)
				)
			)
		)
		(property "MPN" "CR0402-FX-2001GLF"
			(at 0 0 0)
			(unlocked yes)
			(layer "F.Fab")
			(hide yes)
			(effects
				(font
					(size 1 1)
					(thickness 0.15)
				)
			)
		)
		(property "Manufacturer" "Bourns"
			(at 0 0 0)
			(unlocked yes)
			(layer "F.Fab")
			(hide yes)
			(effects
				(font
					(size 1 1)
					(thickness 0.15)
				)
			)
		)
		(property "License" "Apache-2.0"
			(at 0 0 0)
			(unlocked yes)
			(layer "F.Fab")
			(hide yes)
			(effects
				(font
					(size 1 1)
					(thickness 0.15)
				)
			)
		)
		(property "Author" "Antmicro"
			(at 0 0 0)
			(unlocked yes)
			(layer "F.Fab")
			(hide yes)
			(effects
				(font
					(size 1 1)
					(thickness 0.15)
				)
			)
		)
		(property "Val" "2k"
			(at 0 0 0)
			(unlocked yes)
			(layer "F.Fab")
			(hide yes)
			(effects
				(font
					(size 1 1)
					(thickness 0.15)
				)
			)
		)
		(property "Tolerance" "1%"
			(at 0 0 0)
			(unlocked yes)
			(layer "F.Fab")
			(hide yes)
			(effects
				(font
					(size 1 1)
					(thickness 0.15)
				)
			)
		)
		(sheetname "/X710-AT2 Misc/")
		(sheetfile "x710-at2-mics.kicad_sch")
		(attr smd)
		(fp_rect
			(start -0.925 -0.47)
			(end 0.925 0.47)
			(stroke
				(width 0.05)
				(type default)
			)
			(fill no)
			(layer "F.CrtYd")
		)
		(fp_rect
			(start -0.5 -0.25)
			(end 0.5 0.25)
			(stroke
				(width 0.15)
				(type solid)
			)
			(fill no)
			(layer "F.Fab")
		)
		(fp_text user "${REFERENCE}"
			(at -0.95 3.168 0)
			(layer "F.Fab")
			(effects
				(font
					(size 0.7 0.7)
					(thickness 0.15)
				)
				(justify left bottom)
			)
		)
		(fp_text user "Author: Antmicro"
			(at -0.95 4.169 0)
			(layer "F.Fab")
			(effects
				(font
					(size 0.7 0.7)
					(thickness 0.15)
				)
				(justify left bottom)
			)
		)
		(fp_text user "License: Apache-2.0"
			(at -0.95 5.169 0)
			(layer "F.Fab")
			(effects
				(font
					(size 0.7 0.7)
					(thickness 0.15)
				)
				(justify left bottom)
			)
		)
		(pad "1" smd roundrect
			(at -0.48 0)
			(size 0.59 0.64)
			(layers "F.Cu" "F.Mask" "F.Paste")
			(roundrect_rratio 0.25)
			(net 150 "/X710-AT2 Misc/~{PHY_RESET}")
			(pintype "passive")
		)
		(pad "2" smd roundrect
			(at 0.48 0)
			(size 0.59 0.64)
			(layers "F.Cu" "F.Mask" "F.Paste")
			(roundrect_rratio 0.25)
			(net 18 "+1V88")
			(pintype "passive")
		)
	)
	(footprint "antmicro-footprints:R_0402_1005Metric"
		(layer "F.Cu")
		(at 156.205 69.074999 90)
		(descr "Resistor SMD 0402")
		(tags "resistor SMD 0402")
		(property "Reference" "R145"
			(at 11.574999 20.295 90)
			(layer "F.SilkS")
			(effects
				(font
					(size 0.7 0.7)
					(thickness 0.15)
				)
			)
		)
		(property "Value" "R_10k_0402"
			(at -1.011843 1.772047 90)
			(layer "F.Fab")
			(effects
				(font
					(size 0.7 0.7)
					(thickness 0.15)
				)
				(justify left bottom)
			)
		)
		(property "Datasheet" "https://www.bourns.com/docs/product-datasheets/cr.pdf"
			(at 0 0 90)
			(layer "F.Fab")
			(hide yes)
			(effects
				(font
					(size 1.27 1.27)
					(thickness 0.15)
				)
			)
		)
		(property "Description" "SMD Chip Resistor, 10 kohm, ± 1%, 62.5 mW, 0402 [1005 Metric], Thick Film, General Purpose"
			(at 0 0 90)
			(layer "F.Fab")
			(hide yes)
			(effects
				(font
					(size 1.27 1.27)
					(thickness 0.15)
				)
			)
		)
		(property "MPN" "CR0402-FX-1002GLF"
			(at 0 0 90)
			(unlocked yes)
			(layer "F.Fab")
			(hide yes)
			(effects
				(font
					(size 1 1)
					(thickness 0.15)
				)
			)
		)
		(property "Manufacturer" "Bourns"
			(at 0 0 90)
			(unlocked yes)
			(layer "F.Fab")
			(hide yes)
			(effects
				(font
					(size 1 1)
					(thickness 0.15)
				)
			)
		)
		(property "License" "Apache-2.0"
			(at 0 0 90)
			(unlocked yes)
			(layer "F.Fab")
			(hide yes)
			(effects
				(font
					(size 1 1)
					(thickness 0.15)
				)
			)
		)
		(property "Author" "Antmicro"
			(at 0 0 90)
			(unlocked yes)
			(layer "F.Fab")
			(hide yes)
			(effects
				(font
					(size 1 1)
					(thickness 0.15)
				)
			)
		)
		(property "Val" "10k"
			(at 0 0 90)
			(unlocked yes)
			(layer "F.Fab")
			(hide yes)
			(effects
				(font
					(size 1 1)
					(thickness 0.15)
				)
			)
		)
		(property "Tolerance" "1%"
			(at 0 0 90)
			(unlocked yes)
			(layer "F.Fab")
			(hide yes)
			(effects
				(font
					(size 1 1)
					(thickness 0.15)
				)
			)
		)
		(sheetname "/X710-AT2 Misc/")
		(sheetfile "x710-at2-mics.kicad_sch")
		(attr smd)
		(fp_rect
			(start -0.925 -0.47)
			(end 0.925 0.47)
			(stroke
				(width 0.05)
				(type default)
			)
			(fill no)
			(layer "F.CrtYd")
		)
		(fp_rect
			(start -0.5 -0.25)
			(end 0.5 0.25)
			(stroke
				(width 0.15)
				(type solid)
			)
			(fill no)
			(layer "F.Fab")
		)
		(fp_text user "License: Apache-2.0"
			(at -0.95 5.169 90)
			(layer "F.Fab")
			(effects
				(font
					(size 0.7 0.7)
					(thickness 0.15)
				)
				(justify left bottom)
			)
		)
		(fp_text user "Author: Antmicro"
			(at -0.95 4.169 90)
			(layer "F.Fab")
			(effects
				(font
					(size 0.7 0.7)
					(thickness 0.15)
				)
				(justify left bottom)
			)
		)
		(fp_text user "${REFERENCE}"
			(at -0.95 3.168 90)
			(layer "F.Fab")
			(effects
				(font
					(size 0.7 0.7)
					(thickness 0.15)
				)
				(justify left bottom)
			)
		)
		(pad "1" smd roundrect
			(at -0.48 0 90)
			(size 0.59 0.64)
			(layers "F.Cu" "F.Mask" "F.Paste")
			(roundrect_rratio 0.25)
			(net 103 "/X710-AT2 Misc/MAIN_PWR_OK")
			(pintype "passive")
		)
		(pad "2" smd roundrect
			(at 0.48 0 90)
			(size 0.59 0.64)
			(layers "F.Cu" "F.Mask" "F.Paste")
			(roundrect_rratio 0.25)
			(net 7 "+3V3")
			(pintype "passive")
		)
	)
	(footprint "antmicro-footprints:C_0402_1005Metric"
		(layer "F.Cu")
		(at 175.822358 77 90)
		(descr "Capacitor SMD 0402")
		(tags "capacitor SMD 0402")
		(property "Reference" "C275"
			(at -1.4 1.377642 90)
			(layer "F.SilkS")
			(effects
				(font
					(size 0.7 0.7)
					(thickness 0.15)
				)
				(justify left bottom)
			)
		)
		(property "Value" "C_100n_0402"
			(at -1.022927 2.155213 90)
			(layer "F.Fab")
			(effects
				(font
					(size 0.7 0.7)
					(thickness 0.15)
				)
				(justify left bottom)
			)
		)
		(property "Datasheet" "https://www.murata.com/products/productdetail?partno=GRM155R61H104KE14%23"
			(at 0 0 90)
			(layer "F.Fab")
			(hide yes)
			(effects
				(font
					(size 1.27 1.27)
					(thickness 0.15)
				)
			)
		)
		(property "Description" "SMD Multilayer Ceramic Capacitor, 0.1 µF, 50 V, 0402 [1005 Metric], ± 10%, X5R, GRM Series"
			(at 0 0 90)
			(layer "F.Fab")
			(hide yes)
			(effects
				(font
					(size 1.27 1.27)
					(thickness 0.15)
				)
			)
		)
		(property "MPN" "GRM155R61H104KE14D"
			(at 0 0 90)
			(unlocked yes)
			(layer "F.Fab")
			(hide yes)
			(effects
				(font
					(size 1 1)
					(thickness 0.15)
				)
			)
		)
		(property "Val" "100n"
			(at 0 0 90)
			(unlocked yes)
			(layer "F.Fab")
			(hide yes)
			(effects
				(font
					(size 1 1)
					(thickness 0.15)
				)
			)
		)
		(property "Voltage" "50V"
			(at 0 0 90)
			(unlocked yes)
			(layer "F.Fab")
			(hide yes)
			(effects
				(font
					(size 1 1)
					(thickness 0.15)
				)
			)
		)
		(property "Dielectric" "X5R"
			(at 0 0 90)
			(unlocked yes)
			(layer "F.Fab")
			(hide yes)
			(effects
				(font
					(size 1 1)
					(thickness 0.15)
				)
			)
		)
		(property "Manufacturer" "Murata"
			(at 0 0 90)
			(unlocked yes)
			(layer "F.Fab")
			(hide yes)
			(effects
				(font
					(size 1 1)
					(thickness 0.15)
				)
			)
		)
		(property "License" "Apache-2.0"
			(at 0 0 90)
			(unlocked yes)
			(layer "F.Fab")
			(hide yes)
			(effects
				(font
					(size 1 1)
					(thickness 0.15)
				)
			)
		)
		(property "Author" "Antmicro"
			(at 0 0 90)
			(unlocked yes)
			(layer "F.Fab")
			(hide yes)
			(effects
				(font
					(size 1 1)
					(thickness 0.15)
				)
			)
		)
		(sheetname "/X710-AT2 Misc/")
		(sheetfile "x710-at2-mics.kicad_sch")
		(attr smd)
		(fp_rect
			(start -0.925 -0.47)
			(end 0.925 0.47)
			(stroke
				(width 0.05)
				(type default)
			)
			(fill no)
			(layer "F.CrtYd")
		)
		(fp_line
			(start 0.504 -0.25)
			(end 0.504 0.248)
			(stroke
				(width 0.15)
				(type solid)
			)
			(layer "F.Fab")
		)
		(fp_line
			(start -0.494 -0.25)
			(end 0.504 -0.25)
			(stroke
				(width 0.15)
				(type solid)
			)
			(layer "F.Fab")
		)
		(fp_line
			(start 0.504 0.248)
			(end -0.494 0.248)
			(stroke
				(width 0.15)
				(type solid)
			)
			(layer "F.Fab")
		)
		(fp_line
			(start -0.494 0.248)
			(end -0.494 -0.25)
			(stroke
				(width 0.15)
				(type solid)
			)
			(layer "F.Fab")
		)
		(fp_text user "${REFERENCE}"
			(at -0.939 4.599 90)
			(layer "F.Fab")
			(effects
				(font
					(size 0.7 0.7)
					(thickness 0.15)
				)
				(justify left bottom)
			)
		)
		(fp_text user "License: Apache-2.0"
			(at -0.939 5.799 90)
			(layer "F.Fab")
			(effects
				(font
					(size 0.7 0.7)
					(thickness 0.15)
				)
				(justify left bottom)
			)
		)
		(fp_text user "Author: Antmicro"
			(at -0.939 3.399 90)
			(layer "F.Fab")
			(effects
				(font
					(size 0.7 0.7)
					(thickness 0.15)
				)
				(justify left bottom)
			)
		)
		(pad "1" smd roundrect
			(at -0.48 0 90)
			(size 0.59 0.64)
			(layers "F.Cu" "F.Mask" "F.Paste")
			(roundrect_rratio 0.25)
			(net 23 "GND")
			(pintype "passive")
		)
		(pad "2" smd roundrect
			(at 0.48 0 90)
			(size 0.59 0.64)
			(layers "F.Cu" "F.Mask" "F.Paste")
			(roundrect_rratio 0.25)
			(net 7 "+3V3")
			(pintype "passive")
		)
	)
	(footprint "antmicro-footprints:C_0603_1608Metric_EIA"
		(layer "F.Cu")
		(at 135.1 105.600001 90)
		(descr "Capacitor SMD 0603, IPC-7351 Density Level A")
		(tags "Capacitor 0603")
		(property "Reference" "C135"
			(at -17.849995 16.849997 90)
			(layer "F.SilkS")
			(effects
				(font
					(size 0.7 0.7)
					(thickness 0.15)
				)
			)
		)
		(property "Value" "C_22u_16V_0603"
			(at -1.42757 1.770288 90)
			(layer "F.Fab")
			(effects
				(font
					(size 0.7 0.7)
					(thickness 0.15)
				)
				(justify left bottom)
			)
		)
		(property "Datasheet" "https://product.samsungsem.com/mlcc/CL10A226MO7JZN.do"
			(at 0 0 90)
			(layer "F.Fab")
			(hide yes)
			(effects
				(font
					(size 1.27 1.27)
					(thickness 0.15)
				)
			)
		)
		(property "Description" "SMD Multilayer Ceramic Capacitor"
			(at 0 0 90)
			(layer "F.Fab")
			(hide yes)
			(effects
				(font
					(size 1.27 1.27)
					(thickness 0.15)
				)
			)
		)
		(property "MPN" "CL10A226MO7JZNC"
			(at 0 0 90)
			(unlocked yes)
			(layer "F.Fab")
			(hide yes)
			(effects
				(font
					(size 1 1)
					(thickness 0.15)
				)
			)
		)
		(property "Manufacturer" "Samsung Electro-Mechanics"
			(at 0 0 90)
			(unlocked yes)
			(layer "F.Fab")
			(hide yes)
			(effects
				(font
					(size 1 1)
					(thickness 0.15)
				)
			)
		)
		(property "License" "Apache-2.0"
			(at 0 0 90)
			(unlocked yes)
			(layer "F.Fab")
			(hide yes)
			(effects
				(font
					(size 1 1)
					(thickness 0.15)
				)
			)
		)
		(property "Author" "Antmicro"
			(at 0 0 90)
			(unlocked yes)
			(layer "F.Fab")
			(hide yes)
			(effects
				(font
					(size 1 1)
					(thickness 0.15)
				)
			)
		)
		(property "Val" "22u"
			(at 0 0 90)
			(unlocked yes)
			(layer "F.Fab")
			(hide yes)
			(effects
				(font
					(size 1 1)
					(thickness 0.15)
				)
			)
		)
		(property "Voltage" "16V"
			(at 0 0 90)
			(unlocked yes)
			(layer "F.Fab")
			(hide yes)
			(effects
				(font
					(size 1 1)
					(thickness 0.15)
				)
			)
		)
		(property "Dielectric" ""
			(at 0 0 90)
			(unlocked yes)
			(layer "F.Fab")
			(hide yes)
			(effects
				(font
					(size 1 1)
					(thickness 0.15)
				)
			)
		)
		(sheetname "/X710 DCDC converters/")
		(sheetfile "DCDC_converters_X710.kicad_sch")
		(attr smd)
		(fp_line
			(start -0.15 -0.55)
			(end 0.15 -0.55)
			(stroke
				(width 0.15)
				(type solid)
			)
			(layer "F.SilkS")
		)
		(fp_line
			(start -0.15 0.55)
			(end 0.15 0.55)
			(stroke
				(width 0.15)
				(type solid)
			)
			(layer "F.SilkS")
		)
		(fp_rect
			(start -1.25 -0.65)
			(end 1.25 0.65)
			(stroke
				(width 0.05)
				(type solid)
			)
			(fill no)
			(layer "F.CrtYd")
		)
		(fp_rect
			(start -0.8 -0.45)
			(end 0.8 0.45)
			(stroke
				(width 0.15)
				(type solid)
			)
			(fill no)
			(layer "F.Fab")
		)
		(fp_text user "License: Apache-2.0"
			(at -1.682 5.895 90)
			(layer "F.Fab")
			(effects
				(font
					(size 0.7 0.7)
					(thickness 0.15)
				)
				(justify left bottom)
			)
		)
		(fp_text user "Author: Antmicro"
			(at -1.682 4.894 90)
			(layer "F.Fab")
			(effects
				(font
					(size 0.7 0.7)
					(thickness 0.15)
				)
				(justify left bottom)
			)
		)
		(fp_text user "${REFERENCE}"
			(at -1.682 3.895 90)
			(layer "F.Fab")
			(effects
				(font
					(size 0.7 0.7)
					(thickness 0.15)
				)
				(justify left bottom)
			)
		)
		(pad "1" smd roundrect
			(at -0.7 0 90)
			(size 0.8 1.1)
			(layers "F.Cu" "F.Mask" "F.Paste")
			(roundrect_rratio 0.2)
			(net 23 "GND")
			(pintype "passive")
		)
		(pad "2" smd roundrect
			(at 0.7 0 90)
			(size 0.8 1.1)
			(layers "F.Cu" "F.Mask" "F.Paste")
			(roundrect_rratio 0.2)
			(net 335 "/X710 DCDC converters/+VCCD_OUT")
			(pintype "passive")
		)
	)
)
